# Lightning_PEB_EQL.xlsx — Ethernet (si-constraints)
|  |  | MDI/SGMII (diff pair 100±10% ohm ) |  |  |  | W/Sd=4.13/9.37 for outer layout and 4/8 for inner layer  W:trace width Sd:diff Pair space |  |  |
| I210 to RJ45 |  |  |  |  |  |  |  |  |
| I210 to RJ45 |  |  |  |  |  |  |  |  |
| Net Name | PKG Lengths | PCB Net Length | Differential Match | Net Name | PCB Net Length | Differential Match | MB Total Length | Differential Match |
| NIC0_MDI0_N3 |  | 1101.01 |  | NIC0_MDI0_N3_R | 348.53 |  | 1449.54 |  |
| NIC0_MDI0_P3 |  | 1100.06 | yes; within 5mil | NIC0_MDI0_P3_R | 348.1 | yes; within 5mil | 1448.1599999999999 | yes; within 5mil |
| NIC0_MDI0_N2 |  | 948.9 |  | NIC0_MDI0_N2_R | 433.1 |  | 1382 |  |
| NIC0_MDI0_P2 |  | 946.8 | yes; within 5mil | NIC0_MDI0_P2_R | 433.26 | yes; within 5mil | 1380.06 | yes; within 5mil |
| NIC0_MDI0_N1 |  | 1156.94 |  | NIC0_MDI0_N1_R | 355.1 |  | 1512.04 |  |
| NIC0_MDI0_P1 |  | 1156.95 | yes; within 5mil | NIC0_MDI0_P1_R | 355.87 | yes; within 5mil | 1512.8200000000002 | yes; within 5mil |
| NIC0_MDI0_N0 |  | 1272.98 |  | NIC0_MDI0_N0_R | 325.83999999999997 |  | 1598.82 |  |
| NIC0_MDI0_P0 |  | 1275.3800000000001 | yes; within 5mil | NIC0_MDI0_P0_R | 325.37 | yes; within 5mil | 1600.75 | yes; within 5mil |
| I210 to MBP connector |  |  |  |  |  |  |  |  |
| I210 to MBP connector |  |  |  |  |  |  |  |  |
| Net Name | PKG Lengths | PCB Net Length | Differential Match | Net Name | PCB Net Length | Differential Match | MB Total Length | Differential Match |
| NIC0_MDI0_N3 |  | 1101.01 |  | MNG_RX_DN | 2795.66 |  | 3896.67 |  |
| NIC0_MDI0_P3 |  | 1100.06 | yes; within 5mil | MNG_RX_DP | 2792.81 | yes; within 5mil | 3892.87 | yes; within 5mil |
| NIC0_MDI0_N2 |  | 948.9 |  | MNG_TX_DN | 2953.55 |  | 3902.4500000000003 |  |
| NIC0_MDI0_P2 |  | 946.8 | yes; within 5mil | MNG_TX_DP | 2953.27 | yes; within 5mil | 3900.0699999999997 | yes; within 5mil |
